(kicad_pcb
	(version 20241229)
	(generator "pcbnew")
	(generator_version "9.0")
	(general
		(thickness 1.6642)
		(legacy_teardrops no)
	)
	(paper "A3")
	(title_block
		(title "PolarFire SoM")
		(date "2025-07-22")
		(rev "1.1.4")
		(company "Antmicro Ltd")
		(comment 1 "www.antmicro.com")
		(comment 9 "footprints 276-279 of 470")
	)
	(layers
		(0 "F.Cu" mixed)
		(4 "In1.Cu" power)
		(6 "In2.Cu" signal)
		(8 "In3.Cu" power)
		(10 "In4.Cu" signal)
		(12 "In5.Cu" power)
		(14 "In6.Cu" power)
		(16 "In7.Cu" signal)
		(18 "In8.Cu" power)
		(20 "In9.Cu" signal)
		(22 "In10.Cu" power)
		(24 "In11.Cu" signal)
		(26 "In12.Cu" signal)
		(2 "B.Cu" mixed)
		(9 "F.Adhes" user "F.Adhesive")
		(11 "B.Adhes" user "B.Adhesive")
		(13 "F.Paste" user)
		(15 "B.Paste" user)
		(5 "F.SilkS" user "F.Silkscreen")
		(7 "B.SilkS" user "B.Silkscreen")
		(1 "F.Mask" user)
		(3 "B.Mask" user)
		(17 "Dwgs.User" user "User.Drawings")
		(19 "Cmts.User" user "User.Comments")
		(21 "Eco1.User" user "User.Eco1")
		(23 "Eco2.User" user "User.Eco2")
		(25 "Edge.Cuts" user)
		(27 "Margin" user)
		(31 "F.CrtYd" user "F.Courtyard")
		(29 "B.CrtYd" user "B.Courtyard")
		(35 "F.Fab" user)
		(33 "B.Fab" user)
	)
	(footprint "antmicro-footprints:C_0603_1608Metric"
		(layer "B.Cu")
		(at 191.7 126.88 -90)
		(descr "Capacitor SMD 0603")
		(tags "capacitor 0603")
		(property "Reference" "C21"
			(at -0.255 -1.5 90)
			(layer "B.SilkS")
			(effects
				(font
					(size 0.7 0.7)
					(thickness 0.15)
				)
				(justify left bottom mirror)
			)
		)
		(property "Value" "C_47u_0603"
			(at -1.42757 -1.770288 90)
			(layer "B.Fab")
			(hide yes)
			(effects
				(font
					(size 0.7 0.7)
					(thickness 0.15)
				)
				(justify left bottom mirror)
			)
		)
		(property "Datasheet" "https://www.murata.com/products/productdetail?partno=GRM188R60J476ME15%23"
			(at 0 0 270)
			(layer "F.Fab")
			(hide yes)
			(effects
				(font
					(size 1.27 1.27)
					(thickness 0.15)
				)
			)
		)
		(property "Description" "SMD Multilayer Ceramic Capacitor, 47 µF, 6.3 V, 0603 [1608 Metric], ± 20%, X5R, GRM Series"
			(at 0 0 270)
			(layer "F.Fab")
			(hide yes)
			(effects
				(font
					(size 1.27 1.27)
					(thickness 0.15)
				)
			)
		)
		(property "Author" "Antmicro"
			(at 64.82 318.58 0)
			(layer "B.Fab")
			(hide yes)
			(effects
				(font
					(size 1 1)
					(thickness 0.15)
				)
				(justify mirror)
			)
		)
		(property "Capacitance" "47u"
			(at 64.82 318.58 0)
			(layer "B.Fab")
			(hide yes)
			(effects
				(font
					(size 1 1)
					(thickness 0.15)
				)
				(justify mirror)
			)
		)
		(property "Dielectric" "X7R"
			(at 64.82 318.58 0)
			(layer "B.Fab")
			(hide yes)
			(effects
				(font
					(size 1 1)
					(thickness 0.15)
				)
				(justify mirror)
			)
		)
		(property "License" "Apache-2.0"
			(at 64.82 318.58 0)
			(layer "B.Fab")
			(hide yes)
			(effects
				(font
					(size 1 1)
					(thickness 0.15)
				)
				(justify mirror)
			)
		)
		(property "MPN" "GRM188R60J476ME15D"
			(at 64.82 318.58 0)
			(layer "B.Fab")
			(hide yes)
			(effects
				(font
					(size 1 1)
					(thickness 0.15)
				)
				(justify mirror)
			)
		)
		(property "Manufacturer" "Murata"
			(at 64.82 318.58 0)
			(layer "B.Fab")
			(hide yes)
			(effects
				(font
					(size 1 1)
					(thickness 0.15)
				)
				(justify mirror)
			)
		)
		(property "Public" ""
			(at 64.82 318.58 0)
			(layer "B.Fab")
			(hide yes)
			(effects
				(font
					(size 1 1)
					(thickness 0.15)
				)
				(justify mirror)
			)
		)
		(property "Val" "47u"
			(at 64.82 318.58 0)
			(layer "B.Fab")
			(hide yes)
			(effects
				(font
					(size 1 1)
					(thickness 0.15)
				)
				(justify mirror)
			)
		)
		(property "Voltage" "50V"
			(at 64.82 318.58 0)
			(layer "B.Fab")
			(hide yes)
			(effects
				(font
					(size 1 1)
					(thickness 0.15)
				)
				(justify mirror)
			)
		)
		(sheetname "/FPGA Supply/")
		(sheetfile "fpga-supply.kicad_sch")
		(attr smd)
		(fp_line
			(start -0.15 0.4)
			(end 0.15 0.4)
			(stroke
				(width 0.15)
				(type solid)
			)
			(layer "B.SilkS")
		)
		(fp_line
			(start -0.15 -0.4)
			(end 0.15 -0.4)
			(stroke
				(width 0.15)
				(type solid)
			)
			(layer "B.SilkS")
		)
		(fp_rect
			(start -1.25 0.65)
			(end 1.25 -0.65)
			(stroke
				(width 0.05)
				(type solid)
			)
			(fill no)
			(layer "B.CrtYd")
		)
		(fp_rect
			(start -0.8 0.4)
			(end 0.8 -0.4)
			(stroke
				(width 0.15)
				(type solid)
			)
			(fill no)
			(layer "B.Fab")
		)
		(fp_text user "Author: Antmicro"
			(at -1.682 -4.894 90)
			(layer "B.Fab")
			(effects
				(font
					(size 0.7 0.7)
					(thickness 0.15)
				)
				(justify left bottom mirror)
			)
		)
		(fp_text user "${REFERENCE}"
			(at -1.682 -3.895 90)
			(layer "B.Fab")
			(effects
				(font
					(size 0.7 0.7)
					(thickness 0.15)
				)
				(justify left bottom mirror)
			)
		)
		(fp_text user "License: Apache-2.0"
			(at -1.682 -5.895 90)
			(layer "B.Fab")
			(effects
				(font
					(size 0.7 0.7)
					(thickness 0.15)
				)
				(justify left bottom mirror)
			)
		)
		(pad "1" smd roundrect
			(at -0.7 0 270)
			(size 0.8 1)
			(layers "B.Cu" "B.Mask" "B.Paste")
			(roundrect_rratio 0.2)
			(net 417 "GND")
			(pintype "passive")
		)
		(pad "2" smd roundrect
			(at 0.7 0 270)
			(size 0.8 1)
			(layers "B.Cu" "B.Mask" "B.Paste")
			(roundrect_rratio 0.2)
			(net 2 "+1V1")
			(pintype "passive")
		)
	)
	(footprint "antmicro-footprints:C_0402_1005Metric"
		(layer "B.Cu")
		(at 198.94 132.79 90)
		(descr "Capacitor SMD 0402")
		(tags "capacitor SMD 0402")
		(property "Reference" "C50"
			(at 7.19 -9.615 270)
			(layer "B.SilkS")
			(effects
				(font
					(size 0.7 0.7)
					(thickness 0.15)
				)
				(justify left bottom mirror)
			)
		)
		(property "Value" "C_47n_0402"
			(at -1.022927 -2.155213 270)
			(layer "B.Fab")
			(hide yes)
			(effects
				(font
					(size 0.7 0.7)
					(thickness 0.15)
				)
				(justify left bottom mirror)
			)
		)
		(property "Datasheet" "https://www.murata.com/en-us/products/productdetail?partno=GRM155R61C473KA01%23"
			(at 0 0 90)
			(layer "F.Fab")
			(hide yes)
			(effects
				(font
					(size 1.27 1.27)
					(thickness 0.15)
				)
			)
		)
		(property "Description" "SMD Multilayer Ceramic Capacitor, 47000 pF, 16 V, 0402 [1005 Metric], ± 10%, X5R, MC"
			(at 0 0 90)
			(layer "F.Fab")
			(hide yes)
			(effects
				(font
					(size 1.27 1.27)
					(thickness 0.15)
				)
			)
		)
		(property "Author" "Antmicro"
			(at 331.73 -66.15 0)
			(layer "B.Fab")
			(hide yes)
			(effects
				(font
					(size 1 1)
					(thickness 0.15)
				)
				(justify mirror)
			)
		)
		(property "Dielectric" "X5R"
			(at 331.73 -66.15 0)
			(layer "B.Fab")
			(hide yes)
			(effects
				(font
					(size 1 1)
					(thickness 0.15)
				)
				(justify mirror)
			)
		)
		(property "License" "Apache-2.0"
			(at 331.73 -66.15 0)
			(layer "B.Fab")
			(hide yes)
			(effects
				(font
					(size 1 1)
					(thickness 0.15)
				)
				(justify mirror)
			)
		)
		(property "MPN" "GRM155R61C473KA01D"
			(at 331.73 -66.15 0)
			(layer "B.Fab")
			(hide yes)
			(effects
				(font
					(size 1 1)
					(thickness 0.15)
				)
				(justify mirror)
			)
		)
		(property "Manufacturer" "Murata"
			(at 331.73 -66.15 0)
			(layer "B.Fab")
			(hide yes)
			(effects
				(font
					(size 1 1)
					(thickness 0.15)
				)
				(justify mirror)
			)
		)
		(property "Public" ""
			(at 331.73 -66.15 0)
			(layer "B.Fab")
			(hide yes)
			(effects
				(font
					(size 1 1)
					(thickness 0.15)
				)
				(justify mirror)
			)
		)
		(property "Val" "47n"
			(at 331.73 -66.15 0)
			(layer "B.Fab")
			(hide yes)
			(effects
				(font
					(size 1 1)
					(thickness 0.15)
				)
				(justify mirror)
			)
		)
		(property "Voltage" "10V"
			(at 331.73 -66.15 0)
			(layer "B.Fab")
			(hide yes)
			(effects
				(font
					(size 1 1)
					(thickness 0.15)
				)
				(justify mirror)
			)
		)
		(sheetname "/FPGA Supply/")
		(sheetfile "fpga-supply.kicad_sch")
		(attr smd)
		(fp_rect
			(start -0.925 0.47)
			(end 0.925 -0.47)
			(stroke
				(width 0.05)
				(type default)
			)
			(fill no)
			(layer "B.CrtYd")
		)
		(fp_line
			(start 0.504 -0.248)
			(end -0.494 -0.248)
			(stroke
				(width 0.15)
				(type solid)
			)
			(layer "B.Fab")
		)
		(fp_line
			(start -0.494 -0.248)
			(end -0.494 0.25)
			(stroke
				(width 0.15)
				(type solid)
			)
			(layer "B.Fab")
		)
		(fp_line
			(start 0.504 0.25)
			(end 0.504 -0.248)
			(stroke
				(width 0.15)
				(type solid)
			)
			(layer "B.Fab")
		)
		(fp_line
			(start -0.494 0.25)
			(end 0.504 0.25)
			(stroke
				(width 0.15)
				(type solid)
			)
			(layer "B.Fab")
		)
		(fp_text user "${REFERENCE}"
			(at -0.939 -4.599 270)
			(layer "B.Fab")
			(effects
				(font
					(size 0.7 0.7)
					(thickness 0.15)
				)
				(justify left bottom mirror)
			)
		)
		(fp_text user "Author: Antmicro"
			(at -0.939 -3.399 270)
			(layer "B.Fab")
			(effects
				(font
					(size 0.7 0.7)
					(thickness 0.15)
				)
				(justify left bottom mirror)
			)
		)
		(fp_text user "License: Apache-2.0"
			(at -0.939 -5.799 270)
			(layer "B.Fab")
			(effects
				(font
					(size 0.7 0.7)
					(thickness 0.15)
				)
				(justify left bottom mirror)
			)
		)
		(pad "1" smd roundrect
			(at -0.48 0 90)
			(size 0.59 0.64)
			(layers "B.Cu" "B.Mask" "B.Paste")
			(roundrect_rratio 0.25)
			(net 417 "GND")
			(pintype "passive")
		)
		(pad "2" smd roundrect
			(at 0.48 0 90)
			(size 0.59 0.64)
			(layers "B.Cu" "B.Mask" "B.Paste")
			(roundrect_rratio 0.25)
			(net 47 "+1V05")
			(pintype "passive")
		)
	)
	(footprint "antmicro-footprints:R_0402_1005Metric"
		(layer "B.Cu")
		(at 213.861 116.704)
		(descr "Resistor SMD 0402")
		(tags "resistor SMD 0402")
		(property "Reference" "R92"
			(at -24.761 18.271 180)
			(layer "B.SilkS")
			(effects
				(font
					(size 0.7 0.7)
					(thickness 0.15)
				)
				(justify left bottom mirror)
			)
		)
		(property "Value" "R_4k7_0402"
			(at -1.011843 -1.772047 180)
			(layer "B.Fab")
			(hide yes)
			(effects
				(font
					(size 0.7 0.7)
					(thickness 0.15)
				)
				(justify left bottom mirror)
			)
		)
		(property "Datasheet" "https://www.bourns.com/docs/product-datasheets/cr.pdf"
			(at 0 0 0)
			(layer "F.Fab")
			(hide yes)
			(effects
				(font
					(size 1.27 1.27)
					(thickness 0.15)
				)
			)
		)
		(property "Description" "SMD Chip Resistor, 4.7 kohm, ± 1%, 62.5 mW, 0402 [1005 Metric], Thick Film, General Purpose"
			(at 0 0 0)
			(layer "F.Fab")
			(hide yes)
			(effects
				(font
					(size 1.27 1.27)
					(thickness 0.15)
				)
			)
		)
		(property "Author" "Antmicro"
			(at 0 0 0)
			(layer "B.Fab")
			(hide yes)
			(effects
				(font
					(size 1 1)
					(thickness 0.15)
				)
				(justify mirror)
			)
		)
		(property "License" "Apache-2.0"
			(at 0 0 0)
			(layer "B.Fab")
			(hide yes)
			(effects
				(font
					(size 1 1)
					(thickness 0.15)
				)
				(justify mirror)
			)
		)
		(property "MPN" "CR0402-FX-4701GLF"
			(at 0 0 0)
			(layer "B.Fab")
			(hide yes)
			(effects
				(font
					(size 1 1)
					(thickness 0.15)
				)
				(justify mirror)
			)
		)
		(property "Manufacturer" "Bourns"
			(at 0 0 0)
			(layer "B.Fab")
			(hide yes)
			(effects
				(font
					(size 1 1)
					(thickness 0.15)
				)
				(justify mirror)
			)
		)
		(property "Public" ""
			(at 0 0 0)
			(layer "B.Fab")
			(hide yes)
			(effects
				(font
					(size 1 1)
					(thickness 0.15)
				)
				(justify mirror)
			)
		)
		(property "Tolerance" "1%"
			(at 0 0 0)
			(layer "B.Fab")
			(hide yes)
			(effects
				(font
					(size 1 1)
					(thickness 0.15)
				)
				(justify mirror)
			)
		)
		(property "Val" "4k7"
			(at 0 0 0)
			(layer "B.Fab")
			(hide yes)
			(effects
				(font
					(size 1 1)
					(thickness 0.15)
				)
				(justify mirror)
			)
		)
		(sheetname "/Ethernet/")
		(sheetfile "ethernet.kicad_sch")
		(attr smd)
		(fp_rect
			(start -0.925 0.47)
			(end 0.925 -0.47)
			(stroke
				(width 0.05)
				(type default)
			)
			(fill no)
			(layer "B.CrtYd")
		)
		(fp_rect
			(start -0.5 0.25)
			(end 0.5 -0.25)
			(stroke
				(width 0.15)
				(type solid)
			)
			(fill no)
			(layer "B.Fab")
		)
		(fp_text user "${REFERENCE}"
			(at -0.95 -3.168 180)
			(layer "B.Fab")
			(effects
				(font
					(size 0.7 0.7)
					(thickness 0.15)
				)
				(justify left bottom mirror)
			)
		)
		(fp_text user "Author: Antmicro"
			(at -0.95 -4.169 180)
			(layer "B.Fab")
			(effects
				(font
					(size 0.7 0.7)
					(thickness 0.15)
				)
				(justify left bottom mirror)
			)
		)
		(fp_text user "License: Apache-2.0"
			(at -0.95 -5.169 180)
			(layer "B.Fab")
			(effects
				(font
					(size 0.7 0.7)
					(thickness 0.15)
				)
				(justify left bottom mirror)
			)
		)
		(pad "1" smd roundrect
			(at -0.48 0)
			(size 0.59 0.64)
			(layers "B.Cu" "B.Mask" "B.Paste")
			(roundrect_rratio 0.25)
			(net 227 "Net-(U11-GTX_CLK)")
			(pintype "passive")
		)
		(pad "2" smd roundrect
			(at 0.48 0)
			(size 0.59 0.64)
			(layers "B.Cu" "B.Mask" "B.Paste")
			(roundrect_rratio 0.25)
			(net 417 "GND")
			(pintype "passive")
		)
	)
	(footprint "antmicro-footprints:R_0402_1005Metric"
		(layer "B.Cu")
		(at 176.15 146.85 180)
		(descr "Resistor SMD 0402")
		(tags "resistor SMD 0402")
		(property "Reference" "R6"
			(at -0.3 -3.5 0)
			(layer "B.SilkS")
			(effects
				(font
					(size 0.7 0.7)
					(thickness 0.15)
				)
				(justify left bottom mirror)
			)
		)
		(property "Value" "R_10k_0402"
			(at -1.011843 -1.772047 0)
			(layer "B.Fab")
			(hide yes)
			(effects
				(font
					(size 0.7 0.7)
					(thickness 0.15)
				)
				(justify left bottom mirror)
			)
		)
		(property "Datasheet" "https://www.bourns.com/docs/product-datasheets/cr.pdf"
			(at 0 0 180)
			(layer "F.Fab")
			(hide yes)
			(effects
				(font
					(size 1.27 1.27)
					(thickness 0.15)
				)
			)
		)
		(property "Description" "SMD Chip Resistor, 10 kohm, ± 1%, 62.5 mW, 0402 [1005 Metric], Thick Film, General Purpose"
			(at 0 0 180)
			(layer "F.Fab")
			(hide yes)
			(effects
				(font
					(size 1.27 1.27)
					(thickness 0.15)
				)
			)
		)
		(property "Author" "Antmicro"
			(at 352.3 293.7 0)
			(layer "B.Fab")
			(hide yes)
			(effects
				(font
					(size 1 1)
					(thickness 0.15)
				)
				(justify mirror)
			)
		)
		(property "License" "Apache-2.0"
			(at 352.3 293.7 0)
			(layer "B.Fab")
			(hide yes)
			(effects
				(font
					(size 1 1)
					(thickness 0.15)
				)
				(justify mirror)
			)
		)
		(property "MPN" "CR0402-FX-1002GLF"
			(at 352.3 293.7 0)
			(layer "B.Fab")
			(hide yes)
			(effects
				(font
					(size 1 1)
					(thickness 0.15)
				)
				(justify mirror)
			)
		)
		(property "Manufacturer" "Bourns"
			(at 352.3 293.7 0)
			(layer "B.Fab")
			(hide yes)
			(effects
				(font
					(size 1 1)
					(thickness 0.15)
				)
				(justify mirror)
			)
		)
		(property "Public" ""
			(at 352.3 293.7 0)
			(layer "B.Fab")
			(hide yes)
			(effects
				(font
					(size 1 1)
					(thickness 0.15)
				)
				(justify mirror)
			)
		)
		(property "Tolerance" "1%"
			(at 352.3 293.7 0)
			(layer "B.Fab")
			(hide yes)
			(effects
				(font
					(size 1 1)
					(thickness 0.15)
				)
				(justify mirror)
			)
		)
		(property "Val" "10k"
			(at 352.3 293.7 0)
			(layer "B.Fab")
			(hide yes)
			(effects
				(font
					(size 1 1)
					(thickness 0.15)
				)
				(justify mirror)
			)
		)
		(sheetname "/Supply/")
		(sheetfile "supply.kicad_sch")
		(attr smd)
		(fp_rect
			(start -0.925 0.47)
			(end 0.925 -0.47)
			(stroke
				(width 0.05)
				(type default)
			)
			(fill no)
			(layer "B.CrtYd")
		)
		(fp_rect
			(start -0.5 0.25)
			(end 0.5 -0.25)
			(stroke
				(width 0.15)
				(type solid)
			)
			(fill no)
			(layer "B.Fab")
		)
		(fp_text user "License: Apache-2.0"
			(at -0.95 -5.169 0)
			(layer "B.Fab")
			(effects
				(font
					(size 0.7 0.7)
					(thickness 0.15)
				)
				(justify left bottom mirror)
			)
		)
		(fp_text user "Author: Antmicro"
			(at -0.95 -4.169 0)
			(layer "B.Fab")
			(effects
				(font
					(size 0.7 0.7)
					(thickness 0.15)
				)
				(justify left bottom mirror)
			)
		)
		(fp_text user "${REFERENCE}"
			(at -0.95 -3.168 0)
			(layer "B.Fab")
			(effects
				(font
					(size 0.7 0.7)
					(thickness 0.15)
				)
				(justify left bottom mirror)
			)
		)
		(pad "1" smd roundrect
			(at -0.48 0 180)
			(size 0.59 0.64)
			(layers "B.Cu" "B.Mask" "B.Paste")
			(roundrect_rratio 0.25)
			(net 263 "Net-(U6-~{PWRDN})")
			(pintype "passive")
		)
		(pad "2" smd roundrect
			(at 0.48 0 180)
			(size 0.59 0.64)
			(layers "B.Cu" "B.Mask" "B.Paste")
			(roundrect_rratio 0.25)
			(net 649 "VDD")
			(pintype "passive")
		)
	)
)
